# T6G (Grand Teton) — schematic netlist excerpt (pin names and nets, part order shuffled) for the footprints in the layout excerpt that follows; sources: Cadence DE-HDL packaged netlist, KiCad conversion of 04192023_DAF0TMB3IC0_F0TG_MB_C_brd_V02_OCP.brd

R368  Q_RES  4.7K 5% EMPTY  pkg 0402LF  page 160 : A = PVDD18_S5_P0 ; B = SMB_CPU0_CPU1_SEC_SCL_R2
R330  Q_RES  2.2K 5% EMPTY  pkg 0402LF  page 151 : A = SMB_FAN_3V3AUX_SCL ; B = P3V3_AUX

(kicad_pcb
	(version 20260206)
	(generator "pcbnew")
	(generator_version "10.0")
	(general
		(thickness 1.6)
		(legacy_teardrops no)
	)
	(paper "A4")
	(title_block
		(title "04192023_DAF0TMB3IC0_F0TG_MB_C_brd_V02_OCP.brd")
		(comment 1 "Grand Teton / footprints 7160-7161 of 8354")
	)
	(layers
		(0 "F.Cu" signal "TOP")
		(4 "In1.Cu" signal "GND")
		(6 "In2.Cu" signal "IN1")
		(8 "In3.Cu" signal "GND1")
		(10 "In4.Cu" signal "IN2")
		(12 "In5.Cu" signal "GND2")
		(14 "In6.Cu" signal "IN3")
		(16 "In7.Cu" signal "GND3")
		(18 "In8.Cu" signal "VCC")
		(20 "In9.Cu" signal "VCC1")
		(22 "In10.Cu" signal "GND4")
		(24 "In11.Cu" signal "IN4")
		(26 "In12.Cu" signal "GND5")
		(28 "In13.Cu" signal "IN5")
		(30 "In14.Cu" signal "GND6")
		(32 "In15.Cu" signal "IN6")
		(34 "In16.Cu" signal "GND7")
		(2 "B.Cu" signal "BOTTOM")
		(9 "F.Adhes" user "F.Adhesive")
		(11 "B.Adhes" user "B.Adhesive")
		(13 "F.Paste" user "Package Geometry/Pastemask Top")
		(15 "B.Paste" user "Package Geometry/Pastemask Bottom")
		(5 "F.SilkS" user "Ref Des/Silkscreen Top")
		(7 "B.SilkS" user "Ref Des/Silkscreen Bottom")
		(1 "F.Mask" user "Board Geometry/Soldermask Top")
		(3 "B.Mask" user "Board Geometry/Soldermask Bottom")
		(17 "Dwgs.User" user "User.Drawings")
		(19 "Cmts.User" user "User.Comments")
		(21 "Eco1.User" user "User.Eco1")
		(23 "Eco2.User" user "User.Eco2")
		(25 "Edge.Cuts" user "Board Geometry/Outline")
		(27 "Margin" user)
		(31 "F.CrtYd" user "Package Geometry/Place Bound Top")
		(29 "B.CrtYd" user "Package Geometry/Place Bound Bottom")
		(35 "F.Fab" user "Ref Des/Assembly Top")
		(33 "B.Fab" user "Ref Des/Assembly Bottom")
	)
	(footprint ""
		(layer "B.Cu")
		(at 157.61843 -14.143228 180)
		(property "Reference" "R330"
			(at 0 0 0)
			(layer "B.SilkS")
			(hide yes)
			(effects
				(font
					(size 1.27 1.27)
				)
				(justify mirror)
			)
		)
		(property "Value" ""
			(at 0 0 0)
			(layer "B.Fab")
			(effects
				(font
					(size 1.27 1.27)
				)
				(justify mirror)
			)
		)
		(duplicate_pad_numbers_are_jumpers no)
		(fp_line
			(start 0.7874 0.4064)
			(end 0.7874 -0.4064)
			(stroke
				(width 0.1524)
				(type default)
			)
			(layer "B.SilkS")
		)
		(fp_line
			(start 0.7874 -0.4064)
			(end -0.7874 -0.4064)
			(stroke
				(width 0.1524)
				(type default)
			)
			(layer "B.SilkS")
		)
		(fp_line
			(start -0.7874 0.4064)
			(end 0.7874 0.4064)
			(stroke
				(width 0.1524)
				(type default)
			)
			(layer "B.SilkS")
		)
		(fp_line
			(start -0.7874 -0.4064)
			(end -0.7874 0.4064)
			(stroke
				(width 0.1524)
				(type default)
			)
			(layer "B.SilkS")
		)
		(fp_line
			(start 0.67945 0.3048)
			(end 0.67945 -0.305054)
			(stroke
				(width 0.1)
				(type default)
			)
			(layer "B.Fab")
		)
		(fp_line
			(start 0.67945 -0.305054)
			(end 0.12065 -0.305054)
			(stroke
				(width 0.1)
				(type default)
			)
			(layer "B.Fab")
		)
		(fp_line
			(start 0.12065 0.3048)
			(end 0.67945 0.3048)
			(stroke
				(width 0.1)
				(type default)
			)
			(layer "B.Fab")
		)
		(fp_line
			(start 0.12065 0.2794)
			(end 0.12065 0.3048)
			(stroke
				(width 0.1)
				(type default)
			)
			(layer "B.Fab")
		)
		(fp_line
			(start 0.12065 -0.2794)
			(end -0.12065 -0.2794)
			(stroke
				(width 0.1)
				(type default)
			)
			(layer "B.Fab")
		)
		(fp_line
			(start 0.12065 -0.305054)
			(end 0.12065 -0.2794)
			(stroke
				(width 0.1)
				(type default)
			)
			(layer "B.Fab")
		)
		(fp_line
			(start -0.120396 0.3048)
			(end -0.120396 0.2794)
			(stroke
				(width 0.1)
				(type default)
			)
			(layer "B.Fab")
		)
		(fp_line
			(start -0.120396 0.2794)
			(end 0.12065 0.2794)
			(stroke
				(width 0.1)
				(type default)
			)
			(layer "B.Fab")
		)
		(fp_line
			(start -0.12065 -0.2794)
			(end -0.12065 -0.3048)
			(stroke
				(width 0.1)
				(type default)
			)
			(layer "B.Fab")
		)
		(fp_line
			(start -0.12065 -0.3048)
			(end -0.67945 -0.3048)
			(stroke
				(width 0.1)
				(type default)
			)
			(layer "B.Fab")
		)
		(fp_line
			(start -0.67945 0.3048)
			(end -0.120396 0.3048)
			(stroke
				(width 0.1)
				(type default)
			)
			(layer "B.Fab")
		)
		(fp_line
			(start -0.67945 -0.3048)
			(end -0.67945 0.3048)
			(stroke
				(width 0.1)
				(type default)
			)
			(layer "B.Fab")
		)
		(pad "1" smd circle
			(at 0.40005 0)
			(size 0 0)
			(layers "B.Cu" "B.Mask" "B.Paste")
			(net "SMB_FAN_3V3AUX_SCL")
		)
		(pad "2" smd circle
			(at -0.40005 0)
			(size 0 0)
			(layers "B.Cu" "B.Mask" "B.Paste")
			(net "P3V3_AUX")
		)
	)
	(footprint ""
		(layer "B.Cu")
		(at 242.697 -229.489 180)
		(property "Reference" "R368"
			(at 0 0 0)
			(layer "B.SilkS")
			(hide yes)
			(effects
				(font
					(size 1.27 1.27)
				)
				(justify mirror)
			)
		)
		(property "Value" ""
			(at 0 0 0)
			(layer "B.Fab")
			(effects
				(font
					(size 1.27 1.27)
				)
				(justify mirror)
			)
		)
		(duplicate_pad_numbers_are_jumpers no)
		(fp_line
			(start 0.7874 0.4064)
			(end 0.7874 -0.4064)
			(stroke
				(width 0.1524)
				(type default)
			)
			(layer "B.SilkS")
		)
		(fp_line
			(start 0.7874 -0.4064)
			(end -0.7874 -0.4064)
			(stroke
				(width 0.1524)
				(type default)
			)
			(layer "B.SilkS")
		)
		(fp_line
			(start -0.7874 0.4064)
			(end 0.7874 0.4064)
			(stroke
				(width 0.1524)
				(type default)
			)
			(layer "B.SilkS")
		)
		(fp_line
			(start -0.7874 -0.4064)
			(end -0.7874 0.4064)
			(stroke
				(width 0.1524)
				(type default)
			)
			(layer "B.SilkS")
		)
		(fp_line
			(start 0.67945 0.3048)
			(end 0.67945 -0.305054)
			(stroke
				(width 0.1)
				(type default)
			)
			(layer "B.Fab")
		)
		(fp_line
			(start 0.67945 -0.305054)
			(end 0.12065 -0.305054)
			(stroke
				(width 0.1)
				(type default)
			)
			(layer "B.Fab")
		)
		(fp_line
			(start 0.12065 0.3048)
			(end 0.67945 0.3048)
			(stroke
				(width 0.1)
				(type default)
			)
			(layer "B.Fab")
		)
		(fp_line
			(start 0.12065 0.2794)
			(end 0.12065 0.3048)
			(stroke
				(width 0.1)
				(type default)
			)
			(layer "B.Fab")
		)
		(fp_line
			(start 0.12065 -0.2794)
			(end -0.12065 -0.2794)
			(stroke
				(width 0.1)
				(type default)
			)
			(layer "B.Fab")
		)
		(fp_line
			(start 0.12065 -0.305054)
			(end 0.12065 -0.2794)
			(stroke
				(width 0.1)
				(type default)
			)
			(layer "B.Fab")
		)
		(fp_line
			(start -0.120396 0.3048)
			(end -0.120396 0.2794)
			(stroke
				(width 0.1)
				(type default)
			)
			(layer "B.Fab")
		)
		(fp_line
			(start -0.120396 0.2794)
			(end 0.12065 0.2794)
			(stroke
				(width 0.1)
				(type default)
			)
			(layer "B.Fab")
		)
		(fp_line
			(start -0.12065 -0.2794)
			(end -0.12065 -0.3048)
			(stroke
				(width 0.1)
				(type default)
			)
			(layer "B.Fab")
		)
		(fp_line
			(start -0.12065 -0.3048)
			(end -0.67945 -0.3048)
			(stroke
				(width 0.1)
				(type default)
			)
			(layer "B.Fab")
		)
		(fp_line
			(start -0.67945 0.3048)
			(end -0.120396 0.3048)
			(stroke
				(width 0.1)
				(type default)
			)
			(layer "B.Fab")
		)
		(fp_line
			(start -0.67945 -0.3048)
			(end -0.67945 0.3048)
			(stroke
				(width 0.1)
				(type default)
			)
			(layer "B.Fab")
		)
		(pad "1" smd circle
			(at 0.40005 0)
			(size 0 0)
			(layers "B.Cu" "B.Mask" "B.Paste")
			(net "PVDD18_S5_P0")
		)
		(pad "2" smd circle
			(at -0.40005 0)
			(size 0 0)
			(layers "B.Cu" "B.Mask" "B.Paste")
			(net "SMB_CPU0_CPU1_SEC_SCL_R2")
		)
	)
)
